(kicad_pcb
	(version 20260206)
	(generator "pcbnew")
	(generator_version "10.0")
	(general
		(thickness 1.6)
		(legacy_teardrops no)
	)
	(paper "A4")
	(title_block
		(title "peb — Lightning_PEB_BRD.brd")
		(comment 1 "Lightning (Wiwynn / Facebook NVMe JBOF) / footprints 2350-2356 of 2563")
	)
	(layers
		(0 "F.Cu" signal "TOP")
		(4 "In1.Cu" signal "L2GND")
		(6 "In2.Cu" signal "L3")
		(8 "In3.Cu" signal "L4VCC")
		(10 "In4.Cu" signal "L5VCC")
		(12 "In5.Cu" signal "L6")
		(14 "In6.Cu" signal "L7GND")
		(2 "B.Cu" signal "BOTTOM")
		(9 "F.Adhes" user "F.Adhesive")
		(11 "B.Adhes" user "B.Adhesive")
		(13 "F.Paste" user "Package Geometry/Pastemask Top")
		(15 "B.Paste" user "Package Geometry/Pastemask Bottom")
		(5 "F.SilkS" user "Ref Des/Silkscreen Top")
		(7 "B.SilkS" user "Ref Des/Silkscreen Bottom")
		(1 "F.Mask" user "Board Geometry/Soldermask Top")
		(3 "B.Mask" user "Board Geometry/Soldermask Bottom")
		(17 "Dwgs.User" user "User.Drawings")
		(19 "Cmts.User" user "User.Comments")
		(21 "Eco1.User" user "User.Eco1")
		(23 "Eco2.User" user "User.Eco2")
		(25 "Edge.Cuts" user "Board Geometry/Outline")
		(27 "Margin" user)
		(31 "F.CrtYd" user "Package Geometry/Place Bound Top")
		(29 "B.CrtYd" user "Package Geometry/Place Bound Bottom")
		(35 "F.Fab" user "Ref Des/Assembly Top")
		(33 "B.Fab" user "Ref Des/Assembly Bottom")
	)
	(footprint ""
		(layer "B.Cu")
		(at 155.972002 -64.289432 -90)
		(property "Reference" "PC207"
			(at 0 0 90)
			(layer "B.SilkS")
			(hide yes)
			(effects
				(font
					(size 1.27 1.27)
				)
				(justify mirror)
			)
		)
		(property "Value" "SC470P50V2KX-3GP"
			(at -1.1811 -2.7051 270)
			(unlocked yes)
			(layer "B.Fab")
			(hide yes)
			(effects
				(font
					(size 1.016 1.016)
					(thickness 0.1524)
				)
				(justify mirror)
			)
		)
		(property "Device Type" "C402H22"
			(at -1.1811 -4.2291 270)
			(unlocked yes)
			(layer "B.Fab")
			(hide yes)
			(effects
				(font
					(size 1.016 1.016)
					(thickness 0.1524)
				)
				(justify mirror)
			)
		)
		(duplicate_pad_numbers_are_jumpers no)
		(fp_rect
			(start 0.4318 0.9525)
			(end -0.4318 -0.9525)
			(stroke
				(width 0)
				(type default)
			)
			(fill no)
			(layer "B.CrtYd")
		)
		(fp_rect
			(start 0.4318 0.9525)
			(end -0.4318 -0.9525)
			(stroke
				(width 0)
				(type default)
			)
			(fill no)
			(layer "B.Fab")
		)
		(pad "1" smd custom
			(at 0 -0.4445 90)
			(size 0.1524 0.1524)
			(layers "B.Cu" "B.Mask" "B.Paste")
			(net "P0V9_SNB")
			(options
				(clearance outline)
				(anchor circle)
			)
			(primitives
				(gr_poly
					(pts
						(arc
							(start 0.3048 0.2032)
							(mid 0.275042 0.275042)
							(end 0.2032 0.3048)
						)
						(arc
							(start -0.2032 0.3048)
							(mid -0.275042 0.275042)
							(end -0.3048 0.2032)
						)
						(arc
							(start -0.3048 -0.2032)
							(mid -0.275042 -0.275042)
							(end -0.2032 -0.3048)
						)
						(arc
							(start 0.2032 -0.3048)
							(mid 0.275042 -0.275042)
							(end 0.3048 -0.2032)
						)
					)
					(width 0)
					(fill yes)
				)
			)
		)
		(pad "2" smd custom
			(at 0 0.4445 90)
			(size 0.1524 0.1524)
			(layers "B.Cu" "B.Mask" "B.Paste")
			(net "GND")
			(options
				(clearance outline)
				(anchor circle)
			)
			(primitives
				(gr_poly
					(pts
						(arc
							(start 0.3048 0.2032)
							(mid 0.275042 0.275042)
							(end 0.2032 0.3048)
						)
						(arc
							(start -0.2032 0.3048)
							(mid -0.275042 0.275042)
							(end -0.3048 0.2032)
						)
						(arc
							(start -0.3048 -0.2032)
							(mid -0.275042 -0.275042)
							(end -0.2032 -0.3048)
						)
						(arc
							(start 0.2032 -0.3048)
							(mid 0.275042 -0.275042)
							(end 0.3048 -0.2032)
						)
					)
					(width 0)
					(fill yes)
				)
			)
		)
	)
	(footprint ""
		(layer "B.Cu")
		(at 53.721 -137.795 90)
		(property "Reference" "R148"
			(at 0 0 90)
			(layer "B.SilkS")
			(hide yes)
			(effects
				(font
					(size 1.27 1.27)
				)
				(justify mirror)
			)
		)
		(property "Value" "4K7R2F-GP"
			(at -0.064008 -3.993896 90)
			(unlocked yes)
			(layer "B.Fab")
			(hide yes)
			(effects
				(font
					(size 1.016 1.016)
					(thickness 0.1524)
				)
				(justify mirror)
			)
		)
		(property "Device Type" "R402H16"
			(at -0.064008 -5.517896 90)
			(unlocked yes)
			(layer "B.Fab")
			(hide yes)
			(effects
				(font
					(size 1.016 1.016)
					(thickness 0.1524)
				)
				(justify mirror)
			)
		)
		(duplicate_pad_numbers_are_jumpers no)
		(fp_line
			(start 0.508 -0.9398)
			(end 0.508 0.9398)
			(stroke
				(width 0.1524)
				(type default)
			)
			(layer "B.SilkS")
		)
		(fp_line
			(start -0.508 -0.9398)
			(end 0.508 -0.9398)
			(stroke
				(width 0.1524)
				(type default)
			)
			(layer "B.SilkS")
		)
		(fp_rect
			(start 0.508 0.9398)
			(end -0.508 -0.9398)
			(stroke
				(width 0)
				(type default)
			)
			(fill no)
			(layer "B.CrtYd")
		)
		(fp_rect
			(start 0.508 0.9398)
			(end -0.508 -0.9398)
			(stroke
				(width 0)
				(type default)
			)
			(fill no)
			(layer "B.Fab")
		)
		(pad "1" smd custom
			(at 0 -0.4445 270)
			(size 0.1397 0.1397)
			(layers "B.Cu" "B.Mask" "B.Paste")
			(net "CBL_PRSNT_N_3")
			(options
				(clearance outline)
				(anchor circle)
			)
			(primitives
				(gr_poly
					(pts
						(arc
							(start -0.1778 0.2794)
							(mid -0.249642 0.249642)
							(end -0.2794 0.1778)
						)
						(arc
							(start -0.2794 -0.1778)
							(mid -0.249642 -0.249642)
							(end -0.1778 -0.2794)
						)
						(arc
							(start 0.1778 -0.2794)
							(mid 0.249642 -0.249642)
							(end 0.2794 -0.1778)
						)
						(arc
							(start 0.2794 0.1778)
							(mid 0.249642 0.249642)
							(end 0.1778 0.2794)
						)
					)
					(width 0)
					(fill yes)
				)
			)
		)
		(pad "2" smd custom
			(at 0 0.4445 270)
			(size 0.1397 0.1397)
			(layers "B.Cu" "B.Mask" "B.Paste")
			(net "P3V3_STBY")
			(options
				(clearance outline)
				(anchor circle)
			)
			(primitives
				(gr_poly
					(pts
						(arc
							(start -0.1778 0.2794)
							(mid -0.249642 0.249642)
							(end -0.2794 0.1778)
						)
						(arc
							(start -0.2794 -0.1778)
							(mid -0.249642 -0.249642)
							(end -0.1778 -0.2794)
						)
						(arc
							(start 0.1778 -0.2794)
							(mid 0.249642 -0.249642)
							(end 0.2794 -0.1778)
						)
						(arc
							(start 0.2794 0.1778)
							(mid 0.249642 0.249642)
							(end 0.1778 0.2794)
						)
					)
					(width 0)
					(fill yes)
				)
			)
		)
	)
	(footprint ""
		(layer "B.Cu")
		(at 230.251 -20.447)
		(property "Reference" "R3701"
			(at 0 0 0)
			(layer "B.SilkS")
			(hide yes)
			(effects
				(font
					(size 1.27 1.27)
				)
				(justify mirror)
			)
		)
		(property "Value" "4K7R2F-GP"
			(at -0.064008 -3.993896 0)
			(unlocked yes)
			(layer "B.Fab")
			(hide yes)
			(effects
				(font
					(size 1.016 1.016)
					(thickness 0.1524)
				)
				(justify mirror)
			)
		)
		(property "Device Type" "R402H16"
			(at -0.064008 -5.517896 0)
			(unlocked yes)
			(layer "B.Fab")
			(hide yes)
			(effects
				(font
					(size 1.016 1.016)
					(thickness 0.1524)
				)
				(justify mirror)
			)
		)
		(duplicate_pad_numbers_are_jumpers no)
		(fp_line
			(start -0.508 -0.9398)
			(end 0.508 -0.9398)
			(stroke
				(width 0.1524)
				(type default)
			)
			(layer "B.SilkS")
		)
		(fp_line
			(start 0.508 -0.9398)
			(end 0.508 0.9398)
			(stroke
				(width 0.1524)
				(type default)
			)
			(layer "B.SilkS")
		)
		(fp_rect
			(start 0.508 0.9398)
			(end -0.508 -0.9398)
			(stroke
				(width 0)
				(type default)
			)
			(fill no)
			(layer "B.CrtYd")
		)
		(fp_rect
			(start 0.508 0.9398)
			(end -0.508 -0.9398)
			(stroke
				(width 0)
				(type default)
			)
			(fill no)
			(layer "B.Fab")
		)
		(pad "1" smd custom
			(at 0 -0.4445 180)
			(size 0.1397 0.1397)
			(layers "B.Cu" "B.Mask" "B.Paste")
			(net "HOST1_RST_N_LS")
			(options
				(clearance outline)
				(anchor circle)
			)
			(primitives
				(gr_poly
					(pts
						(arc
							(start -0.1778 0.2794)
							(mid -0.249642 0.249642)
							(end -0.2794 0.1778)
						)
						(arc
							(start -0.2794 -0.1778)
							(mid -0.249642 -0.249642)
							(end -0.1778 -0.2794)
						)
						(arc
							(start 0.1778 -0.2794)
							(mid 0.249642 -0.249642)
							(end 0.2794 -0.1778)
						)
						(arc
							(start 0.2794 0.1778)
							(mid 0.249642 0.249642)
							(end 0.1778 0.2794)
						)
					)
					(width 0)
					(fill yes)
				)
			)
		)
		(pad "2" smd custom
			(at 0 0.4445 180)
			(size 0.1397 0.1397)
			(layers "B.Cu" "B.Mask" "B.Paste")
			(net "DUT_VDDO")
			(options
				(clearance outline)
				(anchor circle)
			)
			(primitives
				(gr_poly
					(pts
						(arc
							(start -0.1778 0.2794)
							(mid -0.249642 0.249642)
							(end -0.2794 0.1778)
						)
						(arc
							(start -0.2794 -0.1778)
							(mid -0.249642 -0.249642)
							(end -0.1778 -0.2794)
						)
						(arc
							(start 0.1778 -0.2794)
							(mid 0.249642 -0.249642)
							(end 0.2794 -0.1778)
						)
						(arc
							(start 0.2794 0.1778)
							(mid 0.249642 0.249642)
							(end 0.1778 0.2794)
						)
					)
					(width 0)
					(fill yes)
				)
			)
		)
	)
	(footprint ""
		(layer "B.Cu")
		(at 239.1664 -41.995852 90)
		(property "Reference" "C434"
			(at 0 0 90)
			(layer "B.SilkS")
			(hide yes)
			(effects
				(font
					(size 1.27 1.27)
				)
				(justify mirror)
			)
		)
		(property "Value" "SCD1U16V1KX-1-GP"
			(at 2.8321 -1.7399 90)
			(unlocked yes)
			(layer "B.Fab")
			(hide yes)
			(effects
				(font
					(size 1.016 1.016)
					(thickness 0.1524)
				)
				(justify mirror)
			)
		)
		(property "Device Type" "C0201H13"
			(at 2.8321 -3.2639 90)
			(unlocked yes)
			(layer "B.Fab")
			(hide yes)
			(effects
				(font
					(size 1.016 1.016)
					(thickness 0.1524)
				)
				(justify mirror)
			)
		)
		(duplicate_pad_numbers_are_jumpers no)
		(fp_rect
			(start 0.2794 0.6477)
			(end -0.2794 -0.6477)
			(stroke
				(width 0)
				(type default)
			)
			(fill no)
			(layer "B.CrtYd")
		)
		(fp_rect
			(start 0.2794 0.6477)
			(end -0.2794 -0.6477)
			(stroke
				(width 0)
				(type default)
			)
			(fill no)
			(layer "B.Fab")
		)
		(pad "1" smd custom
			(at 0 -0.2794 270)
			(size 0.0762 0.0762)
			(layers "B.Cu" "B.Mask" "B.Paste")
			(net "DUT_VDD")
			(options
				(clearance outline)
				(anchor circle)
			)
			(primitives
				(gr_poly
					(pts
						(arc
							(start 0.1524 0.127)
							(mid 0.137521 0.162921)
							(end 0.1016 0.1778)
						)
						(arc
							(start -0.1016 0.1778)
							(mid -0.137521 0.162921)
							(end -0.1524 0.127)
						)
						(arc
							(start -0.1524 -0.127)
							(mid -0.137521 -0.162921)
							(end -0.1016 -0.1778)
						)
						(arc
							(start 0.1016 -0.1778)
							(mid 0.137521 -0.162921)
							(end 0.1524 -0.127)
						)
					)
					(width 0)
					(fill yes)
				)
			)
		)
		(pad "2" smd custom
			(at 0 0.2794 270)
			(size 0.0762 0.0762)
			(layers "B.Cu" "B.Mask" "B.Paste")
			(net "GND")
			(options
				(clearance outline)
				(anchor circle)
			)
			(primitives
				(gr_poly
					(pts
						(arc
							(start 0.1524 0.127)
							(mid 0.137521 0.162921)
							(end 0.1016 0.1778)
						)
						(arc
							(start -0.1016 0.1778)
							(mid -0.137521 0.162921)
							(end -0.1524 0.127)
						)
						(arc
							(start -0.1524 -0.127)
							(mid -0.137521 -0.162921)
							(end -0.1016 -0.1778)
						)
						(arc
							(start 0.1016 -0.1778)
							(mid 0.137521 -0.162921)
							(end 0.1524 -0.127)
						)
					)
					(width 0)
					(fill yes)
				)
			)
		)
	)
	(footprint ""
		(layer "B.Cu")
		(at 252.603 -50.995072 -90)
		(property "Reference" "C551"
			(at 0 0 90)
			(layer "B.SilkS")
			(hide yes)
			(effects
				(font
					(size 1.27 1.27)
				)
				(justify mirror)
			)
		)
		(property "Value" "SCD1U16V1KX-1-GP"
			(at 2.8321 -1.7399 270)
			(unlocked yes)
			(layer "B.Fab")
			(hide yes)
			(effects
				(font
					(size 1.016 1.016)
					(thickness 0.1524)
				)
				(justify mirror)
			)
		)
		(property "Device Type" "C0201H13"
			(at 2.8321 -3.2639 270)
			(unlocked yes)
			(layer "B.Fab")
			(hide yes)
			(effects
				(font
					(size 1.016 1.016)
					(thickness 0.1524)
				)
				(justify mirror)
			)
		)
		(duplicate_pad_numbers_are_jumpers no)
		(fp_rect
			(start 0.2794 0.6477)
			(end -0.2794 -0.6477)
			(stroke
				(width 0)
				(type default)
			)
			(fill no)
			(layer "B.CrtYd")
		)
		(fp_rect
			(start 0.2794 0.6477)
			(end -0.2794 -0.6477)
			(stroke
				(width 0)
				(type default)
			)
			(fill no)
			(layer "B.Fab")
		)
		(pad "1" smd custom
			(at 0 -0.2794 90)
			(size 0.0762 0.0762)
			(layers "B.Cu" "B.Mask" "B.Paste")
			(net "DUT_AVD_PCIE")
			(options
				(clearance outline)
				(anchor circle)
			)
			(primitives
				(gr_poly
					(pts
						(arc
							(start 0.1524 0.127)
							(mid 0.137521 0.162921)
							(end 0.1016 0.1778)
						)
						(arc
							(start -0.1016 0.1778)
							(mid -0.137521 0.162921)
							(end -0.1524 0.127)
						)
						(arc
							(start -0.1524 -0.127)
							(mid -0.137521 -0.162921)
							(end -0.1016 -0.1778)
						)
						(arc
							(start 0.1016 -0.1778)
							(mid 0.137521 -0.162921)
							(end 0.1524 -0.127)
						)
					)
					(width 0)
					(fill yes)
				)
			)
		)
		(pad "2" smd custom
			(at 0 0.2794 90)
			(size 0.0762 0.0762)
			(layers "B.Cu" "B.Mask" "B.Paste")
			(net "GND")
			(options
				(clearance outline)
				(anchor circle)
			)
			(primitives
				(gr_poly
					(pts
						(arc
							(start 0.1524 0.127)
							(mid 0.137521 0.162921)
							(end 0.1016 0.1778)
						)
						(arc
							(start -0.1016 0.1778)
							(mid -0.137521 0.162921)
							(end -0.1524 0.127)
						)
						(arc
							(start -0.1524 -0.127)
							(mid -0.137521 -0.162921)
							(end -0.1016 -0.1778)
						)
						(arc
							(start 0.1016 -0.1778)
							(mid 0.137521 -0.162921)
							(end 0.1524 -0.127)
						)
					)
					(width 0)
					(fill yes)
				)
			)
		)
	)
	(footprint ""
		(layer "B.Cu")
		(at 23.45944 -143.51254 180)
		(property "Reference" "R317"
			(at 0 0 0)
			(layer "B.SilkS")
			(hide yes)
			(effects
				(font
					(size 1.27 1.27)
				)
				(justify mirror)
			)
		)
		(property "Value" "8K2R2J-3-GP"
			(at -0.064008 -3.993896 180)
			(unlocked yes)
			(layer "B.Fab")
			(hide yes)
			(effects
				(font
					(size 1.016 1.016)
					(thickness 0.1524)
				)
				(justify mirror)
			)
		)
		(property "Device Type" "R402H16"
			(at -0.064008 -5.517896 180)
			(unlocked yes)
			(layer "B.Fab")
			(hide yes)
			(effects
				(font
					(size 1.016 1.016)
					(thickness 0.1524)
				)
				(justify mirror)
			)
		)
		(duplicate_pad_numbers_are_jumpers no)
		(fp_line
			(start 0.508 -0.9398)
			(end 0.508 0.9398)
			(stroke
				(width 0.1524)
				(type default)
			)
			(layer "B.SilkS")
		)
		(fp_line
			(start -0.508 -0.9398)
			(end 0.508 -0.9398)
			(stroke
				(width 0.1524)
				(type default)
			)
			(layer "B.SilkS")
		)
		(fp_rect
			(start 0.508 0.9398)
			(end -0.508 -0.9398)
			(stroke
				(width 0)
				(type default)
			)
			(fill no)
			(layer "B.CrtYd")
		)
		(fp_rect
			(start 0.508 0.9398)
			(end -0.508 -0.9398)
			(stroke
				(width 0)
				(type default)
			)
			(fill no)
			(layer "B.Fab")
		)
		(pad "1" smd custom
			(at 0 -0.4445)
			(size 0.1397 0.1397)
			(layers "B.Cu" "B.Mask" "B.Paste")
			(net "PD_USB2VRES")
			(options
				(clearance outline)
				(anchor circle)
			)
			(primitives
				(gr_poly
					(pts
						(arc
							(start -0.1778 0.2794)
							(mid -0.249642 0.249642)
							(end -0.2794 0.1778)
						)
						(arc
							(start -0.2794 -0.1778)
							(mid -0.249642 -0.249642)
							(end -0.1778 -0.2794)
						)
						(arc
							(start 0.1778 -0.2794)
							(mid 0.249642 -0.249642)
							(end 0.2794 -0.1778)
						)
						(arc
							(start 0.2794 0.1778)
							(mid 0.249642 0.249642)
							(end 0.1778 0.2794)
						)
					)
					(width 0)
					(fill yes)
				)
			)
		)
		(pad "2" smd custom
			(at 0 0.4445)
			(size 0.1397 0.1397)
			(layers "B.Cu" "B.Mask" "B.Paste")
			(net "GND")
			(options
				(clearance outline)
				(anchor circle)
			)
			(primitives
				(gr_poly
					(pts
						(arc
							(start -0.1778 0.2794)
							(mid -0.249642 0.249642)
							(end -0.2794 0.1778)
						)
						(arc
							(start -0.2794 -0.1778)
							(mid -0.249642 -0.249642)
							(end -0.1778 -0.2794)
						)
						(arc
							(start 0.1778 -0.2794)
							(mid 0.249642 -0.249642)
							(end 0.2794 -0.1778)
						)
						(arc
							(start 0.2794 0.1778)
							(mid 0.249642 0.249642)
							(end 0.1778 0.2794)
						)
					)
					(width 0)
					(fill yes)
				)
			)
		)
	)
	(footprint ""
		(layer "B.Cu")
		(at 127.084328 -33.518856 180)
		(property "Reference" "C221"
			(at 0 0 0)
			(layer "B.SilkS")
			(hide yes)
			(effects
				(font
					(size 1.27 1.27)
				)
				(justify mirror)
			)
		)
		(property "Value" "SCD1U10V2KX-5GP"
			(at -1.1811 -2.7051 180)
			(unlocked yes)
			(layer "B.Fab")
			(hide yes)
			(effects
				(font
					(size 1.016 1.016)
					(thickness 0.1524)
				)
				(justify mirror)
			)
		)
		(property "Device Type" "C402H22"
			(at -1.1811 -4.2291 180)
			(unlocked yes)
			(layer "B.Fab")
			(hide yes)
			(effects
				(font
					(size 1.016 1.016)
					(thickness 0.1524)
				)
				(justify mirror)
			)
		)
		(duplicate_pad_numbers_are_jumpers no)
		(fp_rect
			(start 0.4318 0.9525)
			(end -0.4318 -0.9525)
			(stroke
				(width 0)
				(type default)
			)
			(fill no)
			(layer "B.CrtYd")
		)
		(fp_rect
			(start 0.4318 0.9525)
			(end -0.4318 -0.9525)
			(stroke
				(width 0)
				(type default)
			)
			(fill no)
			(layer "B.Fab")
		)
		(pad "1" smd custom
			(at 0 -0.4445)
			(size 0.1524 0.1524)
			(layers "B.Cu" "B.Mask" "B.Paste")
			(net "GND")
			(options
				(clearance outline)
				(anchor circle)
			)
			(primitives
				(gr_poly
					(pts
						(arc
							(start 0.3048 0.2032)
							(mid 0.275042 0.275042)
							(end 0.2032 0.3048)
						)
						(arc
							(start -0.2032 0.3048)
							(mid -0.275042 0.275042)
							(end -0.3048 0.2032)
						)
						(arc
							(start -0.3048 -0.2032)
							(mid -0.275042 -0.275042)
							(end -0.2032 -0.3048)
						)
						(arc
							(start 0.2032 -0.3048)
							(mid 0.275042 -0.275042)
							(end 0.3048 -0.2032)
						)
					)
					(width 0)
					(fill yes)
				)
			)
		)
		(pad "2" smd custom
			(at 0 0.4445)
			(size 0.1524 0.1524)
			(layers "B.Cu" "B.Mask" "B.Paste")
			(net "P3V3_STBY")
			(options
				(clearance outline)
				(anchor circle)
			)
			(primitives
				(gr_poly
					(pts
						(arc
							(start 0.3048 0.2032)
							(mid 0.275042 0.275042)
							(end 0.2032 0.3048)
						)
						(arc
							(start -0.2032 0.3048)
							(mid -0.275042 0.275042)
							(end -0.3048 0.2032)
						)
						(arc
							(start -0.3048 -0.2032)
							(mid -0.275042 -0.275042)
							(end -0.2032 -0.3048)
						)
						(arc
							(start 0.2032 -0.3048)
							(mid 0.275042 -0.275042)
							(end 0.3048 -0.2032)
						)
					)
					(width 0)
					(fill yes)
				)
			)
		)
	)
)
